#ISCELL
  mstr_misc dns *
  *
#ISCELL
  pure_quanta quanta_title_block_c *
  *
#CELL
  pure_quanta q_res *
  page22_i10
#CELL
  pure_quanta q_res *
  page22_i100
#CELL
  pure_quanta q_res *
  page22_i101
#CELL
  pure_quanta q_res *
  page22_i102
#ISCELL
  logical_power universal_power *
  page22_i103
#ISCELL
  logical_power universal_power *
  page22_i104
#CELL
  pure_quanta q_res *
  page22_i106
#CELL
  pure_quanta q_cap *
  page22_i107
#ISCELL
  standard offpage *
  page22_i11
#CELL
  pure_quanta q_res *
  page22_i12
#ISCELL
  standard offpage *
  page22_i13
#CELL
  pure_quanta mosfet_n *
  page22_i14
#ISCELL
  logical_power universal_power *
  page22_i16
#CELL
  pure_quanta q_cap *
  page22_i17
#ISCELL
  logical_power universal_gnd *
  page22_i18
#CELL
  pure_quanta mmbt39047f *
  page22_i2
#ISCELL
  logical_power universal_gnd *
  page22_i22
#CELL
  pure_quanta q_cap *
  page22_i23
#ISCELL
  logical_power universal_gnd *
  page22_i25
#CELL
  pure_quanta q_res *
  page22_i26
#ISCELL
  logical_power universal_gnd *
  page22_i27
#CELL
  pure_quanta q_diode *
  page22_i28
#ISCELL
  standard offpage *
  page22_i29
#ISCELL
  logical_power universal_gnd *
  page22_i3
#CELL
  pure_quanta q_res *
  page22_i30
#ISCELL
  logical_power universal_gnd *
  page22_i31
#ISCELL
  standard offpage *
  page22_i32
#ISCELL
  logical_power universal_gnd *
  page22_i34
#CELL
  pure_quanta q_res *
  page22_i35
#ISCELL
  logical_power universal_gnd *
  page22_i36
#CELL
  pure_quanta mmbt39047f *
  page22_i4
#CELL
  pure_quanta q_res *
  page22_i41
#CELL
  pure_quanta q_cap *
  page22_i42
#ISCELL
  logical_power universal_gnd *
  page22_i43
#ISCELL
  logical_power universal_power *
  page22_i44
#ISCELL
  logical_power universal_gnd *
  page22_i45
#CELL
  pure_quanta q_cap *
  page22_i46
#ISCELL
  logical_power universal_gnd *
  page22_i48
#CELL
  pure_quanta q_res *
  page22_i49
#CELL
  pure_quanta q_res *
  page22_i5
#ISCELL
  standard offpage *
  page22_i50
#ISCELL
  standard offpage *
  page22_i52
#ISCELL
  logical_power vccaux15 *
  page22_i53
#ISCELL
  logical_power universal_power *
  page22_i54
#CELL
  pure_quanta q_res *
  page22_i55
#ISCELL
  logical_power universal_power *
  page22_i56
#CELL
  pure_quanta q_cap *
  page22_i57
#ISCELL
  logical_power universal_gnd *
  page22_i58
#CELL
  pure_quanta q_cap *
  page22_i59
#ISCELL
  logical_power universal_gnd *
  page22_i6
#ISCELL
  logical_power universal_gnd *
  page22_i61
#CELL
  pure_quanta q_res *
  page22_i65
#ISCELL
  logical_power universal_power *
  page22_i66
#CELL
  pure_quanta q_res *
  page22_i67
#ISCELL
  standard offpage *
  page22_i68
#CELL
  pure_quanta q_res *
  page22_i69
#CELL
  pure_quanta q_res *
  page22_i7
#CELL
  pure_quanta q_res *
  page22_i71
#CELL
  pure_quanta q_res *
  page22_i72
#ISCELL
  standard offpage *
  page22_i73
#CELL
  pure_quanta q_res *
  page22_i74
#ISCELL
  standard offpage *
  page22_i76
#ISCELL
  standard offpage *
  page22_i79
#CELL
  pure_quanta q_res *
  page22_i8
#ISCELL
  logical_power universal_power *
  page22_i80
#CELL
  pure_quanta q_res *
  page22_i81
#ISCELL
  logical_power universal_power *
  page22_i82
#CELL
  pure_quanta q_res *
  page22_i83
#ISCELL
  logical_power universal_power *
  page22_i84
#ISCELL
  logical_power universal_power *
  page22_i85
#CELL
  pure_quanta 74lvc2g07dw7 *
  page22_i87
#CELL
  pure_quanta mc74vhc1g07dft2g *
  page22_i89
#CELL
  pure_quanta q_res *
  page22_i9
#CELL
  pure_quanta tps3808g18dbvr *
  page22_i90
#ISCELL
  standard offpage *
  page22_i91
#CELL
  pure_quanta q_res *
  page22_i92
#CELL
  pure_quanta mc74vhc1g32dtt1g *
  page22_i94
#ISCELL
  logical_power universal_gnd *
  page22_i95
#ISCELL
  logical_power universal_gnd *
  page22_i96
#CELL
  pure_quanta q_cap *
  page22_i97
#ISCELL
  logical_power vccaux15 *
  page22_i98
